.HEADER
BOARD_FILE 3.0 "Creo Elements/Pro 5.0 M210" 2017/07/31.16:42:42 3
16342-2                                 MM        
.END_HEADER
.BOARD_OUTLINE  MCAD
1.60000             
         0           235.00000             1.00000             0.00000
         0           235.00000           183.76393             0.00000
         0           234.89443           184.21115            26.56505
         0           230.27639           193.44721             0.00000
         0           229.38197           194.00000            63.43495
         0           216.00000           194.00000             0.00000
         0           215.00000           193.00000            90.00000
         0           215.00000           161.00000             0.00000
         0           214.00000           160.00000           -90.00000
         0           149.91803           160.00000             0.00000
         0           149.02361           159.44721            63.43495
         0           144.40557           150.21115             0.00000
         0           144.30000           149.76393            26.56505
         0           144.30000            48.00000             0.00000
         0           143.30000            48.00000          -180.00000
         0           104.70000            48.00000             0.00000
         0           103.70000            48.00000          -180.00000
         0           103.70000           183.76393             0.00000
         0           103.59443           184.21115            26.56505
         0            98.97639           193.44721             0.00000
         0            98.08197           194.00000            63.43495
         0             5.61803           194.00000             0.00000
         0             4.72361           193.44721            63.43495
         0             0.10557           184.21115             0.00000
         0             0.00000           183.76393            26.56505
         0             0.00000             1.00000             0.00000
         0             1.00000             0.00000            90.00000
         0            29.53000            -0.00000             0.00000
         0            30.53000             1.00000            90.00000
         0            30.53000           109.05000             0.00000
         0            31.53000           110.05000           -90.00000
         0            72.03000           110.05000             0.00000
         0            73.03000           109.05000           -90.00000
         0            73.03000             1.00000             0.00000
         0            74.03000             0.00000            90.00000
         0           234.00000            -0.00000             0.00000
         0           235.00000             1.00000            90.00000
         1            80.25000           103.35000             0.00000
         1            76.85000           103.35000             0.00000
         1            76.85000           106.75000          -180.00000
         1            80.25000           106.75000             0.00000
         1            80.25000           103.35000          -180.00000
         2            24.50000            58.85000             0.00000
         2            21.10000            58.85000             0.00000
         2            21.10000            62.25000          -180.00000
         2            24.50000            62.25000             0.00000
         2            24.50000            58.85000          -180.00000
         3           177.80000            20.45000             0.00000
         3           177.80000            22.05000             0.00000
         3           181.00000            22.05000          -180.00000
         3           181.00000            20.45000             0.00000
         3           177.80000            20.45000          -180.00000
         4           202.80000            20.45000             0.00000
         4           202.80000            22.05000             0.00000
         4           206.00000            22.05000          -180.00000
         4           206.00000            20.45000             0.00000
         4           202.80000            20.45000          -180.00000
         5           206.00000            50.45000             0.00000
         5           202.80000            50.45000          -180.00000
         5           202.80000            52.05000             0.00000
         5           206.00000            52.05000          -180.00000
         5           206.00000            50.45000             0.00000
         6           177.80000            50.45000             0.00000
         6           177.80000            52.05000             0.00000
         6           181.00000            52.05000          -180.00000
         6           181.00000            50.45000             0.00000
         6           177.80000            50.45000          -180.00000
         7           125.43500            34.85000             0.00000
         7           122.88500            34.85000          -180.00000
         7           125.43500            34.85000          -180.00000
         8           125.36500            41.84000             0.00000
         8           122.95500            41.84000          -180.00000
         8           125.36500            41.84000          -180.00000
         9            43.55000           170.00000             0.00000
         9            39.35000           170.00000          -180.00000
         9            43.55000           170.00000          -180.00000
        10            24.55000           105.05000             0.00000
        10            21.25000           105.05000          -180.00000
        10            24.55000           105.05000          -180.00000
        11            80.15000            40.05000             0.00000
        11            76.85000            40.05000          -180.00000
        11            80.15000            40.05000          -180.00000
        12            19.75000            25.00000             0.00000
        12            16.25000            25.00000          -180.00000
        12            19.75000            25.00000          -180.00000
        13            14.50000           188.00000             0.00000
        13            10.50000           188.00000          -180.00000
        13            14.50000           188.00000          -180.00000
        14           224.50000             8.00000             0.00000
        14           220.50000             8.00000          -180.00000
        14           224.50000             8.00000          -180.00000
        15            81.75000           120.00000             0.00000
        15            78.25000           120.00000          -180.00000
        15            81.75000           120.00000          -180.00000
        16            94.25000           188.00000             0.00000
        16            90.75000           188.00000          -180.00000
        16            94.25000           188.00000          -180.00000
        17           157.25000           154.00000             0.00000
        17           153.75000           154.00000          -180.00000
        17           157.25000           154.00000          -180.00000
        18           104.75000            10.00000             0.00000
        18           101.25000            10.00000          -180.00000
        18           104.75000            10.00000          -180.00000
        19           224.25000           120.00000             0.00000
        19           220.75000           120.00000          -180.00000
        19           224.25000           120.00000          -180.00000
        20           151.75000           120.00000             0.00000
        20           148.25000           120.00000          -180.00000
        20           151.75000           120.00000          -180.00000
        21            19.75000           120.00000             0.00000
        21            16.25000           120.00000          -180.00000
        21            19.75000           120.00000          -180.00000
        22           224.25000           188.00000             0.00000
        22           220.75000           188.00000          -180.00000
        22           224.25000           188.00000          -180.00000
        23           224.25000           154.00000             0.00000
        23           220.75000           154.00000          -180.00000
        23           224.25000           154.00000          -180.00000
        24           151.05000            78.00000             0.00000
        24           147.55000            78.00000          -180.00000
        24           151.05000            78.00000          -180.00000
.END_BOARD_OUTLINE
.DRILLED_HOLES
.END_DRILLED_HOLES
.PLACE_KEEPOUT      UNOWNED
TOP 0.00000        
         0           150.75000           154.00000             0.00000
         0           160.25000           154.00000           180.00000
         0           150.75000           154.00000           180.00000
.END_PLACE_KEEPOUT
.PLACE_KEEPOUT      UNOWNED
TOP 0.00000        
         0             7.75000           188.00000             0.00000
         0            17.25000           188.00000           180.00000
         0             7.75000           188.00000           180.00000
.END_PLACE_KEEPOUT
.PLACE_KEEPOUT      UNOWNED
TOP 0.00000        
         0            37.70000           170.00000             0.00000
         0            45.20000           170.00000           180.00000
         0            37.70000           170.00000           180.00000
.END_PLACE_KEEPOUT
.PLACE_KEEPOUT      UNOWNED
TOP 0.00000        
         0            87.75000           188.00000             0.00000
         0            97.25000           188.00000           180.00000
         0            87.75000           188.00000           180.00000
.END_PLACE_KEEPOUT
.PLACE_KEEPOUT      UNOWNED
TOP 0.00000        
         0            75.25000           120.00000             0.00000
         0            84.75000           120.00000           180.00000
         0            75.25000           120.00000           180.00000
.END_PLACE_KEEPOUT
.PLACE_KEEPOUT      UNOWNED
TOP 0.00000        
         0            78.55000           109.80000             0.00000
         0            92.70000           109.80000             0.00000
         0            92.70000           100.30000             0.00000
         0            78.55000           100.30000             0.00000
         0            78.55000           109.80000          -180.00000
.END_PLACE_KEEPOUT
.PLACE_KEEPOUT      UNOWNED
TOP 0.00000        
         0            11.90000           109.80000             0.00000
         0            11.90000           103.80000             0.00000
         0            18.31742           103.80000             0.00000
         0            22.90000           100.30000            74.74248
         0            22.90000           109.80000           180.00000
         0            11.90000           109.80000             0.00000
.END_PLACE_KEEPOUT
.PLACE_KEEPOUT      UNOWNED
TOP 0.00000        
         0            22.80000            55.80000             0.00000
         0            22.80000            65.30000           180.00000
         0             8.65000            65.30000             0.00000
         0             8.65000            55.80000             0.00000
         0            22.80000            55.80000             0.00000
.END_PLACE_KEEPOUT
.PLACE_KEEPOUT      UNOWNED
TOP 0.00000        
         0            22.75000            25.00000             0.00000
         0            13.25000            25.00000           180.00000
         0            22.75000            25.00000           180.00000
.END_PLACE_KEEPOUT
.PLACE_KEEPOUT      UNOWNED
TOP 0.00000        
         0            78.50000            44.80000             0.00000
         0            78.50000            35.30000           180.00000
         0            89.50000            35.30000             0.00000
         0            89.50000            44.80000             0.00000
         0            78.50000            44.80000             0.00000
.END_PLACE_KEEPOUT
.PLACE_KEEPOUT      UNOWNED
TOP 0.00000        
         0           107.75000            10.00000             0.00000
         0            98.25000            10.00000           180.00000
         0           107.75000            10.00000           180.00000
.END_PLACE_KEEPOUT
.PLACE_KEEPOUT      UNOWNED
TOP 0.00000        
         0           210.40000            10.25000             0.00000
         0           198.40000            10.25000             0.00000
         0           198.40000            21.25000             0.00000
         0           210.40000            21.25000          -180.00000
         0           210.40000            10.25000             0.00000
.END_PLACE_KEEPOUT
.PLACE_KEEPOUT      UNOWNED
TOP 0.00000        
         0           210.40000            40.25000             0.00000
         0           198.40000            40.25000             0.00000
         0           198.40000            51.25000             0.00000
         0           210.40000            51.25000          -180.00000
         0           210.40000            40.25000             0.00000
.END_PLACE_KEEPOUT
.PLACE_KEEPOUT      UNOWNED
TOP 0.00000        
         0           185.40000            40.25000             0.00000
         0           173.40000            40.25000             0.00000
         0           173.40000            51.25000             0.00000
         0           185.40000            51.25000          -180.00000
         0           185.40000            40.25000             0.00000
.END_PLACE_KEEPOUT
.PLACE_KEEPOUT      UNOWNED
TOP 0.00000        
         0           185.40000            10.25000             0.00000
         0           173.40000            10.25000             0.00000
         0           173.40000            21.25000             0.00000
         0           185.40000            21.25000          -180.00000
         0           185.40000            10.25000             0.00000
.END_PLACE_KEEPOUT
.PLACE_KEEPOUT      UNOWNED
TOP 0.00000        
         0           217.75000             8.00000             0.00000
         0           227.25000             8.00000           180.00000
         0           217.75000             8.00000           180.00000
.END_PLACE_KEEPOUT
.PLACE_KEEPOUT      UNOWNED
TOP 0.00000        
         0           145.25000           120.00000             0.00000
         0           154.75000           120.00000           180.00000
         0           145.25000           120.00000           180.00000
.END_PLACE_KEEPOUT
.PLACE_KEEPOUT      UNOWNED
TOP 0.00000        
         0           217.75000           120.00000             0.00000
         0           227.25000           120.00000           180.00000
         0           217.75000           120.00000           180.00000
.END_PLACE_KEEPOUT
.PLACE_KEEPOUT      UNOWNED
TOP 0.00000        
         0            13.25000           120.00000             0.00000
         0            22.75000           120.00000           180.00000
         0            13.25000           120.00000           180.00000
.END_PLACE_KEEPOUT
.PLACE_KEEPOUT      UNOWNED
TOP 0.00000        
         0           217.75000           188.00000             0.00000
         0           227.25000           188.00000           180.00000
         0           217.75000           188.00000           180.00000
.END_PLACE_KEEPOUT
.PLACE_KEEPOUT      UNOWNED
TOP 0.00000        
         0           227.25000           154.00000             0.00000
         0           217.75000           154.00000           180.00000
         0           227.25000           154.00000           180.00000
.END_PLACE_KEEPOUT
.PLACE_KEEPOUT      UNOWNED
TOP 0.00000        
         0           144.55000            78.00000             0.00000
         0           154.05000            78.00000           180.00000
         0           144.55000            78.00000           180.00000
.END_PLACE_KEEPOUT
.PLACE_KEEPOUT      UNOWNED
TOP 0.00000        
         0           225.35000            56.75000             0.00000
         0           215.35000            56.75000             0.00000
         0           215.35000            66.75000             0.00000
         0           225.35000            66.75000             0.00000
         0           225.35000            56.75000             0.00000
.END_PLACE_KEEPOUT
.PLACE_KEEPOUT      UNOWNED
TOP 0.00000        
         0           213.20000           146.00000             0.00000
         0           203.20000           146.00000             0.00000
         0           203.20000           156.00000             0.00000
         0           213.20000           156.00000             0.00000
         0           213.20000           146.00000             0.00000
.END_PLACE_KEEPOUT
.PLACE_KEEPOUT      UNOWNED
TOP 0.00000        
         0           225.00000           172.50000             0.00000
         0           215.00000           172.50000             0.00000
         0           215.00000           182.50000             0.00000
         0           225.00000           182.50000             0.00000
         0           225.00000           172.50000             0.00000
.END_PLACE_KEEPOUT
.PLACE_KEEPOUT      UNOWNED
TOP 0.00000        
         0             6.70000           113.05000             0.00000
         0            85.70000           113.05000             0.00000
         0            85.70000           109.80000             0.00000
         0            78.55000           109.80000             0.00000
         0            78.55000           100.30000           180.00000
         0            85.70000           100.30000             0.00000
         0            85.70000            44.80000             0.00000
         0            78.50000            44.80000             0.00000
         0            78.50000            35.30000           180.00000
         0            85.70000            35.30000             0.00000
         0            85.70000            31.05000             0.00000
         0            82.30000            31.05000             0.00000
         0            82.30000             0.00000             0.00000
         0            74.03000             0.00000             0.00000
         0            73.03000             1.00000           -90.00000
         0            73.03000           109.05000             0.00000
         0            72.03000           110.05000            90.00000
         0            31.53000           110.05000             0.00000
         0            30.53000           109.05000            90.00000
         0            30.53000            48.60000             0.00000
         0             6.70000            48.60000             0.00000
         0             6.70000            55.80000             0.00000
         0            22.80000            55.80000             0.00000
         0            22.80000            65.30000           180.00000
         0             6.70000            65.30000             0.00000
         0             6.70000           103.80000             0.00000
         0            18.31742           103.80000             0.00000
         0            22.90000           100.30000            74.74248
         0            22.90000           109.80000           180.00000
         0             6.70000           109.80000             0.00000
         0             6.70000           113.05000             0.00000
.END_PLACE_KEEPOUT
.PLACE_KEEPOUT      UNOWNED
TOP 1.10000        
         0           210.39941            21.25000             0.00000
         0           216.40000            21.25000             0.00000
         0           216.40000            56.75000             0.00000
         0           215.35000            56.75000             0.00000
         0           215.35000            66.75000             0.00000
         0           216.40000            66.75000             0.00000
         0           216.40000           128.25000             0.00000
         0           167.40000           128.25000             0.00000
         0           167.40000            21.25000             0.00000
         0           173.39941            21.25000             0.00000
         0           185.39941            21.25000          -180.00000
         0           198.39941            21.25000             0.00000
         0           210.39941            21.25000          -180.00000
.END_PLACE_KEEPOUT
.PLACE_KEEPOUT      UNOWNED
TOP 1.10000        
         0           198.40000            40.25000             0.00000
         0           198.40000            51.25000             0.00000
         0           210.40000            51.25000          -180.00000
         0           210.40000            40.25000             0.00000
         0           198.40000            40.25000             0.00000
.END_PLACE_KEEPOUT
.PLACE_KEEPOUT      UNOWNED
TOP 1.10000        
         0           173.40000            40.25000             0.00000
         0           173.40000            51.25000             0.00000
         0           185.40000            51.25000          -180.00000
         0           185.40000            40.25000             0.00000
         0           173.40000            40.25000             0.00000
.END_PLACE_KEEPOUT
.PLACE_KEEPOUT      UNOWNED
TOP 0.00000        
         0           234.00000             0.00000             0.00000
         0           235.00000             1.00000            90.00000
         0           235.00000           183.76393             0.00000
         0           234.89443           184.21115            26.56505
         0           230.27639           193.44721             0.00000
         0           230.00000           193.78615            25.26224
         0           230.00000             0.00000             0.00000
         0           234.00000             0.00000             0.00000
.END_PLACE_KEEPOUT
.PLACE_KEEPOUT      UNOWNED
TOP 0.00000        
         0             1.00000            -0.00000             0.00000
         0             5.00000            -0.00000             0.00000
         0             5.00000           193.78615             0.00000
         0             4.72361           193.44721            25.26224
         0             0.10557           184.21115             0.00000
         0             0.00000           183.76393            26.56505
         0             0.00000             1.00000             0.00000
         0             1.00000             0.00000            90.00000
.END_PLACE_KEEPOUT
.PLACE_KEEPOUT      UNOWNED
TOP 6.00000        
         0            29.50000            32.00000             0.00000
         0             5.50000            32.00000             0.00000
         0             5.50000            44.00000             0.00000
         0            29.50000            44.00000             0.00000
         0            29.50000            32.00000             0.00000
.END_PLACE_KEEPOUT
.PLACE_KEEPOUT      UNOWNED
TOP 9.30000        
         0            73.43000           129.52000             0.00000
         0            73.43000           113.20000             0.00000
         0            24.60000           113.20000             0.00000
         0            24.60000           129.52000             0.00000
         0            73.43000           129.52000             0.00000
.END_PLACE_KEEPOUT
.PLACE_KEEPOUT      UNOWNED
TOP 4.00000        
         0            17.25000           188.00000             0.00000
         0             7.75000           188.00000           180.00000
         0            17.25000           188.00000           180.00000
.END_PLACE_KEEPOUT
.PLACE_KEEPOUT      UNOWNED
TOP 4.00000        
         0            37.70000           170.00000             0.00000
         0            45.20000           170.00000           180.00000
         0            37.70000           170.00000           180.00000
.END_PLACE_KEEPOUT
.PLACE_KEEPOUT      UNOWNED
TOP 4.00000        
         0            97.25000           188.00000             0.00000
         0            87.75000           188.00000           180.00000
         0            97.25000           188.00000           180.00000
.END_PLACE_KEEPOUT
.PLACE_KEEPOUT      UNOWNED
TOP 4.00000        
         0            22.75000           120.00000             0.00000
         0            13.25000           120.00000           180.00000
         0            22.75000           120.00000           180.00000
.END_PLACE_KEEPOUT
.PLACE_KEEPOUT      UNOWNED
TOP 4.00000        
         0            84.75000           120.00000             0.00000
         0            75.25000           120.00000           180.00000
         0            84.75000           120.00000           180.00000
.END_PLACE_KEEPOUT
.PLACE_KEEPOUT      UNOWNED
TOP 4.00000        
         0            22.75000            25.00000             0.00000
         0            13.25000            25.00000           180.00000
         0            22.75000            25.00000           180.00000
.END_PLACE_KEEPOUT
.PLACE_KEEPOUT      UNOWNED
TOP 4.00000        
         0           107.75000            10.00000             0.00000
         0            98.25000            10.00000           180.00000
         0           107.75000            10.00000           180.00000
.END_PLACE_KEEPOUT
.PLACE_KEEPOUT      UNOWNED
TOP 4.00000        
         0           227.25000             8.00000             0.00000
         0           217.75000             8.00000           180.00000
         0           227.25000             8.00000           180.00000
.END_PLACE_KEEPOUT
.PLACE_KEEPOUT      UNOWNED
TOP 4.00000        
         0           154.75000           120.00000             0.00000
         0           145.25000           120.00000           180.00000
         0           154.75000           120.00000           180.00000
.END_PLACE_KEEPOUT
.PLACE_KEEPOUT      UNOWNED
TOP 4.00000        
         0           227.25000           120.00000             0.00000
         0           217.75000           120.00000           180.00000
         0           227.25000           120.00000           180.00000
.END_PLACE_KEEPOUT
.PLACE_KEEPOUT      UNOWNED
TOP 4.00000        
         0           160.25000           154.00000             0.00000
         0           150.75000           154.00000           180.00000
         0           160.25000           154.00000           180.00000
.END_PLACE_KEEPOUT
.PLACE_KEEPOUT      UNOWNED
TOP 4.00000        
         0           210.40000            21.25000             0.00000
         0           210.40000            10.25000             0.00000
         0           198.40000            10.25000             0.00000
         0           198.40000            21.25000             0.00000
         0           185.39941            21.25000             0.00000
         0           185.40000            10.25000             0.00000
         0           173.40000            10.25000             0.00000
         0           173.40000            21.25000             0.00000
         0           167.40000            21.25000             0.00000
         0           167.40000           128.25000             0.00000
         0           216.40000           128.25000             0.00000
         0           216.40000            66.75000             0.00000
         0           225.35000            66.75000             0.00000
         0           225.35000            56.75000             0.00000
         0           216.40000            56.75000             0.00000
         0           216.40000            21.25000             0.00000
         0           210.39941            21.25000             0.00000
.END_PLACE_KEEPOUT
.PLACE_KEEPOUT      UNOWNED
TOP 4.00000        
         0           227.25000           188.00000             0.00000
         0           217.75000           188.00000           180.00000
         0           227.25000           188.00000           180.00000
.END_PLACE_KEEPOUT
.PLACE_KEEPOUT      UNOWNED
TOP 4.00000        
         0           217.75000           154.00000             0.00000
         0           227.25000           154.00000           180.00000
         0           217.75000           154.00000           180.00000
.END_PLACE_KEEPOUT
.PLACE_KEEPOUT      UNOWNED
TOP 4.00000        
         0             5.50000            32.00000             0.00000
         0             5.50000            44.00000             0.00000
         0            29.50000            44.00000             0.00000
         0            29.50000            32.10000             0.00000
         0            30.53000            32.10000             0.00000
         0            30.53000            48.60000             0.00000
         0             6.70000            48.60000             0.00000
         0             6.70000            55.80000             0.00000
         0             8.65000            55.80000             0.00000
         0             8.65000            65.30000             0.00000
         0             6.70000            65.30000             0.00000
         0             6.70000           103.80000             0.00000
         0            11.90000           103.80000             0.00000
         0            11.90000           109.80000             0.00000
         0             6.70000           109.80000             0.00000
         0             6.70000           113.05000             0.00000
         0            85.70000           113.05000             0.00000
         0            85.70000           109.80000             0.00000
         0            92.70000           109.80000             0.00000
         0            92.70000           100.30000             0.00000
         0            85.70000           100.30000             0.00000
         0            85.70000            44.80000             0.00000
         0            89.50000            44.80000             0.00000
         0            89.50000            35.30000             0.00000
         0            85.70000            35.30000             0.00000
         0            85.70000            31.05000             0.00000
         0            82.30000            31.05000             0.00000
         0            82.30000            -0.00000             0.00000
         0           230.00000            -0.00000             0.00000
         0           230.00000           193.78615             0.00000
         0           229.38197           194.00000            38.17271
         0           216.00000           194.00000             0.00000
         0           215.00000           193.00000            90.00000
         0           215.00000           161.00000             0.00000
         0           214.00000           160.00000           -90.00000
         0           149.91803           160.00000             0.00000
         0           149.02361           159.44721            63.43495
         0           144.40557           150.21115             0.00000
         0           144.30000           149.76393            26.56505
         0           144.30000            48.00000             0.00000
         0           143.30000            48.00000          -180.00000
         0           104.70000            48.00000             0.00000
         0           103.70000            48.00000          -180.00000
         0           103.70000           129.42000             0.00000
         0            73.43000           129.42000             0.00000
         0            73.43000           113.20000             0.00000
         0            24.60000           113.20000             0.00000
         0            24.60000           129.52000             0.00000
         0            73.43000           129.52000             0.00000
         0           103.70000           129.52000             0.00000
         0           103.70000           183.76393             0.00000
         0           103.59443           184.21115            26.56505
         0            98.97639           193.44721             0.00000
         0            98.08197           194.00000            63.43495
         0             5.61803           194.00000             0.00000
         0             5.00000           193.78615            38.17271
         0             5.00000            -0.00000             0.00000
         0            29.53000            -0.00000             0.00000
         0            30.53000             1.00000            90.00000
         0            30.53000            32.00000             0.00000
         0            29.50000            32.00000             0.00000
         0             5.50000            32.00000             0.00000
.END_PLACE_KEEPOUT
.PLACE_KEEPOUT      UNOWNED
TOP 4.00000        
         0           154.05000            78.00000             0.00000
         0           144.55000            78.00000           180.00000
         0           154.05000            78.00000           180.00000
.END_PLACE_KEEPOUT
.PLACE_KEEPOUT      UNOWNED
TOP 4.00000        
         0           213.20000           156.00000             0.00000
         0           213.20000           146.00000             0.00000
         0           203.20000           146.00000             0.00000
         0           203.20000           156.00000             0.00000
         0           213.20000           156.00000             0.00000
.END_PLACE_KEEPOUT
.PLACE_KEEPOUT      UNOWNED
TOP 4.00000        
         0           215.00000           172.50000             0.00000
         0           215.00000           182.50000             0.00000
         0           225.00000           182.50000             0.00000
         0           225.00000           172.50000             0.00000
         0           215.00000           172.50000             0.00000
.END_PLACE_KEEPOUT
.PLACE_KEEPOUT      UNOWNED
BOTTOM 0.00000        
         0             1.00000             0.00000             0.00000
         0             0.00000             1.00000           -90.00000
         0             0.00000           183.76393             0.00000
         0             0.10557           184.21115           -26.56505
         0             4.72361           193.44721             0.00000
         0             5.00000           193.78615           -25.26224
         0             5.00000            -0.00000             0.00000
         0             1.00000            -0.00000             0.00000
.END_PLACE_KEEPOUT
.PLACE_KEEPOUT      UNOWNED
BOTTOM 0.00000        
         0           230.00000           193.78615             0.00000
         0           230.00000             0.00000             0.00000
         0           234.00000            -0.00000             0.00000
         0           235.00000             1.00000            90.00000
         0           235.00000           183.76393             0.00000
         0           234.89443           184.21115            26.56505
         0           230.27639           193.44721             0.00000
         0           230.00000           193.78615            25.26224
.END_PLACE_KEEPOUT
.PLACE_KEEPOUT      UNOWNED
BOTTOM 0.00000        
         0            97.25000           188.00000             0.00000
         0            87.75000           188.00000          -180.00000
         0            97.25000           188.00000          -180.00000
.END_PLACE_KEEPOUT
.PLACE_KEEPOUT      UNOWNED
BOTTOM 0.00000        
         0            17.25000           188.00000             0.00000
         0             7.75000           188.00000          -180.00000
         0            17.25000           188.00000          -180.00000
.END_PLACE_KEEPOUT
.PLACE_KEEPOUT      UNOWNED
BOTTOM 0.00000        
         0            45.20000           170.00000             0.00000
         0            37.70000           170.00000          -180.00000
         0            45.20000           170.00000          -180.00000
.END_PLACE_KEEPOUT
.PLACE_KEEPOUT      UNOWNED
BOTTOM 0.00000        
         0            84.75000           120.00000             0.00000
         0            75.25000           120.00000          -180.00000
         0            84.75000           120.00000          -180.00000
.END_PLACE_KEEPOUT
.PLACE_KEEPOUT      UNOWNED
BOTTOM 0.00000        
         0            83.30000           105.05000             0.00000
         0            73.80000           105.05000          -180.00000
         0            83.30000           105.05000          -180.00000
.END_PLACE_KEEPOUT
.PLACE_KEEPOUT      UNOWNED
BOTTOM 0.00000        
         0            27.65000           105.05000             0.00000
         0            18.15000           105.05000          -180.00000
         0            27.65000           105.05000          -180.00000
.END_PLACE_KEEPOUT
.PLACE_KEEPOUT      UNOWNED
BOTTOM 0.00000        
         0            22.75000           120.00000             0.00000
         0            13.25000           120.00000          -180.00000
         0            22.75000           120.00000          -180.00000
.END_PLACE_KEEPOUT
.PLACE_KEEPOUT      UNOWNED
BOTTOM 0.00000        
         0            83.25000            40.05000             0.00000
         0            73.75000            40.05000          -180.00000
         0            83.25000            40.05000          -180.00000
.END_PLACE_KEEPOUT
.PLACE_KEEPOUT      UNOWNED
BOTTOM 0.00000        
         0            27.55000            60.55000             0.00000
         0            18.05000            60.55000          -180.00000
         0            27.55000            60.55000          -180.00000
.END_PLACE_KEEPOUT
.PLACE_KEEPOUT      UNOWNED
BOTTOM 0.00000        
         0            22.75000            25.00000             0.00000
         0            13.25000            25.00000          -180.00000
         0            22.75000            25.00000          -180.00000
.END_PLACE_KEEPOUT
.PLACE_KEEPOUT      UNOWNED
BOTTOM 0.00000        
         0           107.75000            10.00000             0.00000
         0            98.25000            10.00000          -180.00000
         0           107.75000            10.00000          -180.00000
.END_PLACE_KEEPOUT
.PLACE_KEEPOUT      UNOWNED
BOTTOM 0.00000        
         0           127.16000            34.85000             0.00000
         0           121.16000            34.85000          -180.00000
         0           127.16000            34.85000          -180.00000
.END_PLACE_KEEPOUT
.PLACE_KEEPOUT      UNOWNED
BOTTOM 0.00000        
         0           184.15000            21.25000             0.00000
         0           174.65000            21.25000          -180.00000
         0           184.15000            21.25000          -180.00000
.END_PLACE_KEEPOUT
.PLACE_KEEPOUT      UNOWNED
BOTTOM 0.00000        
         0           209.15000            21.25000             0.00000
         0           199.65000            21.25000          -180.00000
         0           209.15000            21.25000          -180.00000
.END_PLACE_KEEPOUT
.PLACE_KEEPOUT      UNOWNED
BOTTOM 0.00000        
         0           227.25000             8.00000             0.00000
         0           217.75000             8.00000          -180.00000
         0           227.25000             8.00000          -180.00000
.END_PLACE_KEEPOUT
.PLACE_KEEPOUT      UNOWNED
BOTTOM 0.00000        
         0           209.15000            51.25000             0.00000
         0           199.65000            51.25000          -180.00000
         0           209.15000            51.25000          -180.00000
.END_PLACE_KEEPOUT
.PLACE_KEEPOUT      UNOWNED
BOTTOM 0.00000        
         0           184.15000            51.25000             0.00000
         0           174.65000            51.25000          -180.00000
         0           184.15000            51.25000          -180.00000
.END_PLACE_KEEPOUT
.PLACE_KEEPOUT      UNOWNED
BOTTOM 0.00000        
         0           227.25000           120.00000             0.00000
         0           217.75000           120.00000          -180.00000
         0           227.25000           120.00000          -180.00000
.END_PLACE_KEEPOUT
.PLACE_KEEPOUT      UNOWNED
BOTTOM 0.00000        
         0           154.75000           120.00000             0.00000
         0           145.25000           120.00000          -180.00000
         0           154.75000           120.00000          -180.00000
.END_PLACE_KEEPOUT
.PLACE_KEEPOUT      UNOWNED
BOTTOM 0.00000        
         0           160.25000           154.00000             0.00000
         0           150.75000           154.00000          -180.00000
         0           160.25000           154.00000          -180.00000
.END_PLACE_KEEPOUT
.PLACE_KEEPOUT      UNOWNED
BOTTOM 0.00000        
         0           227.25000           188.00000             0.00000
         0           217.75000           188.00000          -180.00000
         0           227.25000           188.00000          -180.00000
.END_PLACE_KEEPOUT
.PLACE_KEEPOUT      UNOWNED
BOTTOM 0.00000        
         0           217.75000           154.00000             0.00000
         0           227.25000           154.00000          -180.00000
         0           217.75000           154.00000          -180.00000
.END_PLACE_KEEPOUT
.PLACE_KEEPOUT      UNOWNED
BOTTOM 0.00000        
         0           154.05000            78.00000             0.00000
         0           144.55000            78.00000          -180.00000
         0           154.05000            78.00000          -180.00000
.END_PLACE_KEEPOUT
.PLACE_KEEPOUT      UNOWNED
BOTTOM 2.00000        
         0           229.38197           194.00000             0.00000
         0           230.00000           193.78615           -38.17271
         0           230.00000            -0.00000             0.00000
         0            74.03000            -0.00000             0.00000
         0            73.03000             1.00000           -90.00000
         0            73.03000           109.05000             0.00000
         0            72.03000           110.05000            90.00000
         0            31.53000           110.05000             0.00000
         0            30.53000           109.05000            90.00000
         0            30.53000             1.00000             0.00000
         0            29.53000             0.00000           -90.00000
         0             5.00000            -0.00000             0.00000
         0             5.00000           193.78615             0.00000
         0             5.61803           194.00000           -38.17271
         0            98.08197           194.00000             0.00000
         0            98.97639           193.44721           -63.43495
         0           103.59443           184.21115             0.00000
         0           103.70000           183.76393           -26.56505
         0           103.70000            48.00000             0.00000
         0           104.70000            48.00000           180.00000
         0           143.30000            48.00000             0.00000
         0           144.30000            48.00000           180.00000
         0           144.30000           149.76393             0.00000
         0           144.40557           150.21115           -26.56505
         0           149.02361           159.44721             0.00000
         0           149.91803           160.00000           -63.43495
         0           214.00000           160.00000             0.00000
         0           215.00000           161.00000            90.00000
         0           215.00000           193.00000             0.00000
         0           216.00000           194.00000           -90.00000
         0           229.38197           194.00000             0.00000
.END_PLACE_KEEPOUT
.PLACE_KEEPOUT      UNOWNED
BOTTOM 2.00000        
         0             7.75000           188.00000             0.00000
         0            17.25000           188.00000          -180.00000
         0             7.75000           188.00000          -180.00000
.END_PLACE_KEEPOUT
.PLACE_KEEPOUT      UNOWNED
BOTTOM 2.00000        
         0            87.75000           188.00000             0.00000
         0            97.25000           188.00000          -180.00000
         0            87.75000           188.00000          -180.00000
.END_PLACE_KEEPOUT
.PLACE_KEEPOUT      UNOWNED
BOTTOM 2.00000        
         0            13.25000           120.00000             0.00000
         0            22.75000           120.00000          -180.00000
         0            13.25000           120.00000          -180.00000
.END_PLACE_KEEPOUT
.PLACE_KEEPOUT      UNOWNED
BOTTOM 2.00000        
         0            75.25000           120.00000             0.00000
         0            84.75000           120.00000          -180.00000
         0            75.25000           120.00000          -180.00000
.END_PLACE_KEEPOUT
.PLACE_KEEPOUT      UNOWNED
BOTTOM 2.00000        
         0            73.80000           105.05000             0.00000
         0            83.30000           105.05000          -180.00000
         0            73.80000           105.05000          -180.00000
.END_PLACE_KEEPOUT
.PLACE_KEEPOUT      UNOWNED
BOTTOM 2.00000        
         0            18.15000           105.05000             0.00000
         0            27.65000           105.05000          -180.00000
         0            18.15000           105.05000          -180.00000
.END_PLACE_KEEPOUT
.PLACE_KEEPOUT      UNOWNED
BOTTOM 2.00000        
         0            37.70000           170.00000             0.00000
         0            45.20000           170.00000          -180.00000
         0            37.70000           170.00000          -180.00000
.END_PLACE_KEEPOUT
.PLACE_KEEPOUT      UNOWNED
BOTTOM 2.00000        
         0            13.25000            25.00000             0.00000
         0            22.75000            25.00000          -180.00000
         0            13.25000            25.00000          -180.00000
.END_PLACE_KEEPOUT
.PLACE_KEEPOUT      UNOWNED
BOTTOM 2.00000        
         0            73.75000            40.05000             0.00000
         0            83.25000            40.05000          -180.00000
         0            73.75000            40.05000          -180.00000
.END_PLACE_KEEPOUT
.PLACE_KEEPOUT      UNOWNED
BOTTOM 2.00000        
         0            98.25000            10.00000             0.00000
         0           107.75000            10.00000          -180.00000
         0            98.25000            10.00000          -180.00000
.END_PLACE_KEEPOUT
.PLACE_KEEPOUT      UNOWNED
BOTTOM 2.00000        
         0           121.16000            34.85000             0.00000
         0           127.16000            34.85000          -180.00000
         0           121.16000            34.85000          -180.00000
.END_PLACE_KEEPOUT
.PLACE_KEEPOUT      UNOWNED
BOTTOM 2.00000        
         0           174.65000            21.25000             0.00000
         0           184.15000            21.25000          -180.00000
         0           174.65000            21.25000          -180.00000
.END_PLACE_KEEPOUT
.PLACE_KEEPOUT      UNOWNED
BOTTOM 2.00000        
         0           174.65000            51.25000             0.00000
         0           184.15000            51.25000          -180.00000
         0           174.65000            51.25000          -180.00000
.END_PLACE_KEEPOUT
.PLACE_KEEPOUT      UNOWNED
BOTTOM 2.00000        
         0           199.65000            51.25000             0.00000
         0           209.15000            51.25000          -180.00000
         0           199.65000            51.25000          -180.00000
.END_PLACE_KEEPOUT
.PLACE_KEEPOUT      UNOWNED
BOTTOM 2.00000        
         0           199.65000            21.25000             0.00000
         0           209.15000            21.25000          -180.00000
         0           199.65000            21.25000          -180.00000
.END_PLACE_KEEPOUT
.PLACE_KEEPOUT      UNOWNED
BOTTOM 2.00000        
         0           217.75000             8.00000             0.00000
         0           227.25000             8.00000          -180.00000
         0           217.75000             8.00000          -180.00000
.END_PLACE_KEEPOUT
.PLACE_KEEPOUT      UNOWNED
BOTTOM 2.00000        
         0           144.55000            78.00000             0.00000
         0           154.05000            78.00000          -180.00000
         0           144.55000            78.00000          -180.00000
.END_PLACE_KEEPOUT
.PLACE_KEEPOUT      UNOWNED
BOTTOM 2.00000        
         0           227.25000           120.00000             0.00000
         0           217.75000           120.00000          -180.00000
         0           227.25000           120.00000          -180.00000
.END_PLACE_KEEPOUT
.PLACE_KEEPOUT      UNOWNED
BOTTOM 2.00000        
         0           145.25000           120.00000             0.00000
         0           154.75000           120.00000          -180.00000
         0           145.25000           120.00000          -180.00000
.END_PLACE_KEEPOUT
.PLACE_KEEPOUT      UNOWNED
BOTTOM 2.00000        
         0           217.75000           154.00000             0.00000
         0           227.25000           154.00000          -180.00000
         0           217.75000           154.00000          -180.00000
.END_PLACE_KEEPOUT
.PLACE_KEEPOUT      UNOWNED
BOTTOM 2.00000        
         0           150.75000           154.00000             0.00000
         0           160.25000           154.00000          -180.00000
         0           150.75000           154.00000          -180.00000
.END_PLACE_KEEPOUT
.PLACE_KEEPOUT      UNOWNED
BOTTOM 2.00000        
         0           217.75000           188.00000             0.00000
         0           227.25000           188.00000          -180.00000
         0           217.75000           188.00000          -180.00000
.END_PLACE_KEEPOUT
.PLACE_KEEPOUT      UNOWNED
BOTTOM 2.00000        
         0            18.05000            60.55000             0.00000
         0            27.55000            60.55000          -180.00000
         0            18.05000            60.55000          -180.00000
.END_PLACE_KEEPOUT
.PLACE_KEEPOUT      UNOWNED
BOTTOM 2.00000        
         0           125.36500            41.84000             0.00000
         0           122.95500            41.84000          -180.00000
         0           125.36500            41.84000          -180.00000
.END_PLACE_KEEPOUT
.ROUTE_KEEPOUT  UNOWNED
TOP
         0             7.75000           188.00000             0.00000
         0            17.25000           188.00000           180.00000
         0             7.75000           188.00000           180.00000
.END_ROUTE_KEEPOUT
.ROUTE_KEEPOUT  UNOWNED
TOP
         0            87.75000           188.00000             0.00000
         0            97.25000           188.00000           180.00000
         0            87.75000           188.00000           180.00000
.END_ROUTE_KEEPOUT
.ROUTE_KEEPOUT  UNOWNED
TOP
         0            84.75000           120.00000             0.00000
         0            75.25000           120.00000           180.00000
         0            84.75000           120.00000           180.00000
.END_ROUTE_KEEPOUT
.ROUTE_KEEPOUT  UNOWNED
TOP
         0            37.70000           170.00000             0.00000
         0            45.20000           170.00000           180.00000
         0            37.70000           170.00000           180.00000
.END_ROUTE_KEEPOUT
.ROUTE_KEEPOUT  UNOWNED
TOP
         0            78.55000           109.80000             0.00000
         0            92.70000           109.80000             0.00000
         0            92.70000           100.30000             0.00000
         0            78.55000           100.30000             0.00000
         0            78.55000           109.80000          -180.00000
.END_ROUTE_KEEPOUT
.ROUTE_KEEPOUT  UNOWNED
TOP
         0            11.90000           109.80000             0.00000
         0            11.90000           103.80000             0.00000
         0            18.31742           103.80000             0.00000
         0            22.90000           100.30000            74.74248
         0            22.90000           109.80000           180.00000
         0            11.90000           109.80000             0.00000
.END_ROUTE_KEEPOUT
.ROUTE_KEEPOUT  UNOWNED
TOP
         0            22.80000            55.80000             0.00000
         0            22.80000            65.30000           180.00000
         0             8.65000            65.30000             0.00000
         0             8.65000            55.80000             0.00000
         0            22.80000            55.80000             0.00000
.END_ROUTE_KEEPOUT
.ROUTE_KEEPOUT  UNOWNED
TOP
         0            78.50000            44.80000             0.00000
         0            78.50000            35.30000           180.00000
         0            89.50000            35.30000             0.00000
         0            89.50000            44.80000             0.00000
         0            78.50000            44.80000             0.00000
.END_ROUTE_KEEPOUT
.ROUTE_KEEPOUT  UNOWNED
TOP
         0           107.75000            10.00000             0.00000
         0            98.25000            10.00000           180.00000
         0           107.75000            10.00000           180.00000
.END_ROUTE_KEEPOUT
.ROUTE_KEEPOUT  UNOWNED
TOP
         0            13.25000            25.00000             0.00000
         0            22.75000            25.00000           180.00000
         0            13.25000            25.00000           180.00000
.END_ROUTE_KEEPOUT
.ROUTE_KEEPOUT  UNOWNED
TOP
         0           227.25000             8.00000             0.00000
         0           217.75000             8.00000           180.00000
         0           227.25000             8.00000           180.00000
.END_ROUTE_KEEPOUT
.ROUTE_KEEPOUT  UNOWNED
TOP
         0           150.75000           154.00000             0.00000
         0           160.25000           154.00000           180.00000
         0           150.75000           154.00000           180.00000
.END_ROUTE_KEEPOUT
.ROUTE_KEEPOUT  UNOWNED
TOP
         0           217.75000           120.00000             0.00000
         0           227.25000           120.00000           180.00000
         0           217.75000           120.00000           180.00000
.END_ROUTE_KEEPOUT
.ROUTE_KEEPOUT  UNOWNED
TOP
         0           145.25000           120.00000             0.00000
         0           154.75000           120.00000           180.00000
         0           145.25000           120.00000           180.00000
.END_ROUTE_KEEPOUT
.ROUTE_KEEPOUT  UNOWNED
TOP
         0            13.25000           120.00000             0.00000
         0            22.75000           120.00000           180.00000
         0            13.25000           120.00000           180.00000
.END_ROUTE_KEEPOUT
.ROUTE_KEEPOUT  UNOWNED
TOP
         0           217.75000           188.00000             0.00000
         0           227.25000           188.00000           180.00000
         0           217.75000           188.00000           180.00000
.END_ROUTE_KEEPOUT
.ROUTE_KEEPOUT  UNOWNED
TOP
         0           227.25000           154.00000             0.00000
         0           217.75000           154.00000           180.00000
         0           227.25000           154.00000           180.00000
.END_ROUTE_KEEPOUT
.ROUTE_KEEPOUT  UNOWNED
TOP
         0           144.55000            78.00000             0.00000
         0           154.05000            78.00000           180.00000
         0           144.55000            78.00000           180.00000
.END_ROUTE_KEEPOUT
.ROUTE_KEEPOUT  UNOWNED
TOP
         0           185.40000            10.25000             0.00000
         0           173.40000            10.25000             0.00000
         0           173.40000            21.25000             0.00000
         0           185.40000            21.25000          -180.00000
         0           185.40000            10.25000             0.00000
.END_ROUTE_KEEPOUT
.ROUTE_KEEPOUT  UNOWNED
TOP
         0           210.40000            10.25000             0.00000
         0           198.40000            10.25000             0.00000
         0           198.40000            21.25000             0.00000
         0           210.40000            21.25000          -180.00000
         0           210.40000            10.25000             0.00000
.END_ROUTE_KEEPOUT
.ROUTE_KEEPOUT  UNOWNED
TOP
         0           185.40000            40.25000             0.00000
         0           173.40000            40.25000             0.00000
         0           173.40000            51.25000             0.00000
         0           185.40000            51.25000          -180.00000
         0           185.40000            40.25000             0.00000
.END_ROUTE_KEEPOUT
.ROUTE_KEEPOUT  UNOWNED
TOP
         0           210.40000            51.25000             0.00000
         0           210.40000            40.25000             0.00000
         0           198.40000            40.25000             0.00000
         0           198.40000            51.25000             0.00000
         0           210.40000            51.25000          -180.00000
.END_ROUTE_KEEPOUT
.ROUTE_KEEPOUT  UNOWNED
BOTTOM
         0           227.25000           188.00000             0.00000
         0           217.75000           188.00000          -180.00000
         0           227.25000           188.00000          -180.00000
.END_ROUTE_KEEPOUT
.ROUTE_KEEPOUT  UNOWNED
BOTTOM
         0           160.25000           154.00000             0.00000
         0           150.75000           154.00000          -180.00000
         0           160.25000           154.00000          -180.00000
.END_ROUTE_KEEPOUT
.ROUTE_KEEPOUT  UNOWNED
BOTTOM
         0            97.25000           188.00000             0.00000
         0            87.75000           188.00000          -180.00000
         0            97.25000           188.00000          -180.00000
.END_ROUTE_KEEPOUT
.ROUTE_KEEPOUT  UNOWNED
BOTTOM
         0            45.20000           170.00000             0.00000
         0            37.70000           170.00000          -180.00000
         0            45.20000           170.00000          -180.00000
.END_ROUTE_KEEPOUT
.ROUTE_KEEPOUT  UNOWNED
BOTTOM
         0            17.25000           188.00000             0.00000
         0             7.75000           188.00000          -180.00000
         0            17.25000           188.00000          -180.00000
.END_ROUTE_KEEPOUT
.ROUTE_KEEPOUT  UNOWNED
BOTTOM
         0            22.75000           120.00000             0.00000
         0            13.25000           120.00000          -180.00000
         0            22.75000           120.00000          -180.00000
.END_ROUTE_KEEPOUT
.ROUTE_KEEPOUT  UNOWNED
BOTTOM
         0            27.65000           105.05000             0.00000
         0            18.15000           105.05000          -180.00000
         0            27.65000           105.05000          -180.00000
.END_ROUTE_KEEPOUT
.ROUTE_KEEPOUT  UNOWNED
BOTTOM
         0            84.75000           120.00000             0.00000
         0            75.25000           120.00000          -180.00000
         0            84.75000           120.00000          -180.00000
.END_ROUTE_KEEPOUT
.ROUTE_KEEPOUT  UNOWNED
BOTTOM
         0            83.30000           105.05000             0.00000
         0            73.80000           105.05000          -180.00000
         0            83.30000           105.05000          -180.00000
.END_ROUTE_KEEPOUT
.ROUTE_KEEPOUT  UNOWNED
BOTTOM
         0            83.25000            40.05000             0.00000
         0            73.75000            40.05000          -180.00000
         0            83.25000            40.05000          -180.00000
.END_ROUTE_KEEPOUT
.ROUTE_KEEPOUT  UNOWNED
BOTTOM
         0            22.75000            25.00000             0.00000
         0            13.25000            25.00000          -180.00000
         0            22.75000            25.00000          -180.00000
.END_ROUTE_KEEPOUT
.ROUTE_KEEPOUT  UNOWNED
BOTTOM
         0            27.55000            60.55000             0.00000
         0            18.05000            60.55000          -180.00000
         0            27.55000            60.55000          -180.00000
.END_ROUTE_KEEPOUT
.ROUTE_KEEPOUT  UNOWNED
BOTTOM
         0           107.75000            10.00000             0.00000
         0            98.25000            10.00000          -180.00000
         0           107.75000            10.00000          -180.00000
.END_ROUTE_KEEPOUT
.ROUTE_KEEPOUT  UNOWNED
BOTTOM
         0           127.16000            34.85000             0.00000
         0           121.16000            34.85000          -180.00000
         0           127.16000            34.85000          -180.00000
.END_ROUTE_KEEPOUT
.ROUTE_KEEPOUT  UNOWNED
BOTTOM
         0           154.75000           120.00000             0.00000
         0           145.25000           120.00000          -180.00000
         0           154.75000           120.00000          -180.00000
.END_ROUTE_KEEPOUT
.ROUTE_KEEPOUT  UNOWNED
BOTTOM
         0           227.25000           120.00000             0.00000
         0           217.75000           120.00000          -180.00000
         0           227.25000           120.00000          -180.00000
.END_ROUTE_KEEPOUT
.ROUTE_KEEPOUT  UNOWNED
BOTTOM
         0           209.15000            51.25000             0.00000
         0           199.65000            51.25000          -180.00000
         0           209.15000            51.25000          -180.00000
.END_ROUTE_KEEPOUT
.ROUTE_KEEPOUT  UNOWNED
BOTTOM
         0           184.15000            51.25000             0.00000
         0           174.65000            51.25000          -180.00000
         0           184.15000            51.25000          -180.00000
.END_ROUTE_KEEPOUT
.ROUTE_KEEPOUT  UNOWNED
BOTTOM
         0           227.25000             8.00000             0.00000
         0           217.75000             8.00000          -180.00000
         0           227.25000             8.00000          -180.00000
.END_ROUTE_KEEPOUT
.ROUTE_KEEPOUT  UNOWNED
BOTTOM
         0           209.15000            21.25000             0.00000
         0           199.65000            21.25000          -180.00000
         0           209.15000            21.25000          -180.00000
.END_ROUTE_KEEPOUT
.ROUTE_KEEPOUT  UNOWNED
BOTTOM
         0           184.15000            21.25000             0.00000
         0           174.65000            21.25000          -180.00000
         0           184.15000            21.25000          -180.00000
.END_ROUTE_KEEPOUT
.ROUTE_KEEPOUT  UNOWNED
BOTTOM
         0           227.25000           154.00000             0.00000
         0           217.75000           154.00000          -180.00000
         0           227.25000           154.00000          -180.00000
.END_ROUTE_KEEPOUT
.ROUTE_KEEPOUT  UNOWNED
BOTTOM
         0           154.05000            78.00000             0.00000
         0           144.55000            78.00000          -180.00000
         0           154.05000            78.00000          -180.00000
.END_ROUTE_KEEPOUT
.PLACEMENT
020_80818_0001 020_80818_0001 CN1           
141.30000      44.20000       0.00000        180.00000      TOP       PLACED         
071_02500_0B0U 071_02500_0B0U U2            
47.70000       145.00000      0.00000        270.00000      TOP       PLACED         
20_F1354_120   20_F1354_120   MEZZ1         
77.70000       72.55000       0.00000        270.00000      TOP       PLACED         
020_C0085_0075 020_C0085_0075 M1            
204.40000      129.60000      0.00000        0.00000        TOP       PLACED         
020_C0085_0075 020_C0085_0075 M2            
179.40000      129.60000      0.00000        0.00000        TOP       PLACED         
022_40001_0221 022_40001_0221 PWR1          
24.00000       8.75000        0.00000        0.00000        TOP       PLACED         
022_40001_0681 022_40001_0681 RST1          
12.00000       6.25000        0.00000        0.00000        TOP       PLACED         
022_10005_0I61 022_10005_0I61 USB1          
88.90000       12.65000       -0.00000       0.00000        TOP       PLACED         
06_WP130_14A   06_WP130_14A   LED3          
206.00000      6.20000        0.00000        0.00000        TOP       PLACED         
020_F0528_0011 020_F0528_0011 TPM1          
54.28000       172.70000      0.00000        0.00000        TOP       PLACED         
087_71242_0465 087_71242_0465 NUT1          
41.45000       170.00000      0.00000        0.00000        TOP       PLACED         
.END_PLACEMENT
